(kicad_pcb
	(version 20241229)
	(generator "pcbnew")
	(generator_version "9.0")
	(general
		(thickness 1.59)
		(legacy_teardrops no)
	)
	(paper "A3")
	(title_block
		(title "usb-c-power-adapter")
		(date "2025-06-24")
		(rev "1.1.2")
		(company "Antmicro")
		(comment 9 "footprints 1-8 of 122")
	)
	(layers
		(0 "F.Cu" signal)
		(4 "In1.Cu" signal)
		(6 "In2.Cu" signal)
		(2 "B.Cu" signal)
		(9 "F.Adhes" user "F.Adhesive")
		(11 "B.Adhes" user "B.Adhesive")
		(13 "F.Paste" user)
		(15 "B.Paste" user)
		(5 "F.SilkS" user "F.Silkscreen")
		(7 "B.SilkS" user "B.Silkscreen")
		(1 "F.Mask" user)
		(3 "B.Mask" user)
		(17 "Dwgs.User" user "User.Drawings")
		(19 "Cmts.User" user "User.Comments")
		(21 "Eco1.User" user "User.Eco1")
		(23 "Eco2.User" user "User.Eco2")
		(25 "Edge.Cuts" user)
		(27 "Margin" user)
		(31 "F.CrtYd" user "F.Courtyard")
		(29 "B.CrtYd" user "B.Courtyard")
		(35 "F.Fab" user)
		(33 "B.Fab" user)
	)
	(footprint "antmicro-footprints:MP_Pad3.5mm_Drill2.2mm"
		(locked yes)
		(layer "F.Cu")
		(at 94.448823 75.686319)
		(property "Reference" "MP1"
			(at -1.103823 0.259681 0)
			(layer "F.SilkS")
			(hide yes)
			(effects
				(font
					(size 0.7 0.7)
					(thickness 0.15)
				)
				(justify left bottom)
			)
		)
		(property "Value" "MP_Pad3.5mm_Drill2.2mm"
			(at 0 2.8 0)
			(layer "F.Fab")
			(effects
				(font
					(size 0.7 0.7)
					(thickness 0.15)
				)
				(justify left bottom)
			)
		)
		(property "Description" "PCB mounting point"
			(at 0 0 0)
			(layer "F.Fab")
			(hide yes)
			(effects
				(font
					(size 1.27 1.27)
					(thickness 0.15)
				)
			)
		)
		(property "Author" "Antmicro"
			(at 0 0 0)
			(unlocked yes)
			(layer "F.Fab")
			(hide yes)
			(effects
				(font
					(size 1 1)
					(thickness 0.15)
				)
			)
		)
		(property "License" "Apache-2.0"
			(at 0 0 0)
			(unlocked yes)
			(layer "F.Fab")
			(hide yes)
			(effects
				(font
					(size 1 1)
					(thickness 0.15)
				)
			)
		)
		(sheetname "/USB PD/")
		(sheetfile "usb_pd.kicad_sch")
		(attr exclude_from_bom)
		(fp_circle
			(center 0 0)
			(end 2 0)
			(stroke
				(width 0.05)
				(type default)
			)
			(fill no)
			(layer "F.CrtYd")
		)
		(pad "1" thru_hole circle
			(at 0 0)
			(size 3.5 3.5)
			(drill 2.2)
			(layers "*.Cu" "*.Mask")
			(remove_unused_layers no)
			(net 2 "GND")
			(pintype "passive")
			(solder_paste_margin_ratio -1)
		)
	)
	(footprint "antmicro-footprints:TP_SMD_0.75mm"
		(layer "F.Cu")
		(at 82.706 74.34)
		(property "Reference" "TP10"
			(at -2.9718 -0.254 90)
			(layer "F.SilkS")
			(hide yes)
			(effects
				(font
					(size 0.7 0.7)
					(thickness 0.15)
				)
				(justify left bottom)
			)
		)
		(property "Value" "TP_0.75mm_SMD"
			(at 0 1.2 0)
			(layer "F.Fab")
			(effects
				(font
					(size 0.7 0.7)
					(thickness 0.15)
				)
				(justify left bottom)
			)
		)
		(property "Description" "SMT test point"
			(at 0 0 0)
			(layer "F.Fab")
			(hide yes)
			(effects
				(font
					(size 1.27 1.27)
					(thickness 0.15)
				)
			)
		)
		(property "MPN" ""
			(at 0 0 0)
			(unlocked yes)
			(layer "F.Fab")
			(hide yes)
			(effects
				(font
					(size 1 1)
					(thickness 0.15)
				)
			)
		)
		(property "Manufacturer" ""
			(at 0 0 0)
			(unlocked yes)
			(layer "F.Fab")
			(hide yes)
			(effects
				(font
					(size 1 1)
					(thickness 0.15)
				)
			)
		)
		(property "Author" "Antmicro"
			(at 0 0 0)
			(unlocked yes)
			(layer "F.Fab")
			(hide yes)
			(effects
				(font
					(size 1 1)
					(thickness 0.15)
				)
			)
		)
		(property "License" "Apache-2.0"
			(at 0 0 0)
			(unlocked yes)
			(layer "F.Fab")
			(hide yes)
			(effects
				(font
					(size 1 1)
					(thickness 0.15)
				)
			)
		)
		(sheetname "/USB PD/")
		(sheetfile "usb_pd.kicad_sch")
		(attr exclude_from_bom)
		(fp_circle
			(center 0 0)
			(end 0.475 0)
			(stroke
				(width 0.05)
				(type default)
			)
			(fill no)
			(layer "F.CrtYd")
		)
		(pad "1" smd circle
			(at 0 0)
			(size 0.75 0.75)
			(layers "F.Cu" "F.Mask")
			(net 55 "Net-(U1-ATTACH)")
			(pinfunction "1")
			(pintype "passive")
		)
	)
	(footprint "antmicro-footprints:R_0402_1005Metric"
		(layer "F.Cu")
		(at 100 81.577 180)
		(descr "Resistor SMD 0402")
		(tags "resistor SMD 0402")
		(property "Reference" "R7"
			(at -1.092 -0.465 0)
			(layer "F.SilkS")
			(effects
				(font
					(size 0.7 0.7)
					(thickness 0.15)
				)
				(justify left bottom)
			)
		)
		(property "Value" "R_68k_0402"
			(at -1.011843 1.772047 0)
			(layer "F.Fab")
			(effects
				(font
					(size 0.7 0.7)
					(thickness 0.15)
				)
				(justify right bottom)
			)
		)
		(property "Datasheet" "https://www.bourns.com/docs/product-datasheets/cr.pdf"
			(at 0 0 180)
			(layer "F.Fab")
			(hide yes)
			(effects
				(font
					(size 1.27 1.27)
					(thickness 0.15)
				)
			)
		)
		(property "Description" "SMD Chip Resistor"
			(at 0 0 180)
			(layer "F.Fab")
			(hide yes)
			(effects
				(font
					(size 1.27 1.27)
					(thickness 0.15)
				)
			)
		)
		(property "MPN" "CR0402-FX-6802GLF"
			(at 0 0 180)
			(unlocked yes)
			(layer "F.Fab")
			(hide yes)
			(effects
				(font
					(size 1 1)
					(thickness 0.15)
				)
			)
		)
		(property "Manufacturer" "Bourns"
			(at 0 0 180)
			(unlocked yes)
			(layer "F.Fab")
			(hide yes)
			(effects
				(font
					(size 1 1)
					(thickness 0.15)
				)
			)
		)
		(property "License" "Apache-2.0"
			(at 0 0 180)
			(unlocked yes)
			(layer "F.Fab")
			(hide yes)
			(effects
				(font
					(size 1 1)
					(thickness 0.15)
				)
			)
		)
		(property "Author" "Antmicro"
			(at 0 0 180)
			(unlocked yes)
			(layer "F.Fab")
			(hide yes)
			(effects
				(font
					(size 1 1)
					(thickness 0.15)
				)
			)
		)
		(property "Val" "68k"
			(at 0 0 180)
			(unlocked yes)
			(layer "F.Fab")
			(hide yes)
			(effects
				(font
					(size 1 1)
					(thickness 0.15)
				)
			)
		)
		(property "Tolerance" "1%"
			(at 0 0 180)
			(unlocked yes)
			(layer "F.Fab")
			(hide yes)
			(effects
				(font
					(size 1 1)
					(thickness 0.15)
				)
			)
		)
		(sheetname "/DC-DC Converters/")
		(sheetfile "dc-dc_converters.kicad_sch")
		(attr smd exclude_from_pos_files exclude_from_bom dnp)
		(fp_rect
			(start -0.925 -0.47)
			(end 0.925 0.47)
			(stroke
				(width 0.05)
				(type default)
			)
			(fill no)
			(layer "F.CrtYd")
		)
		(fp_rect
			(start -0.5 -0.25)
			(end 0.5 0.25)
			(stroke
				(width 0.15)
				(type solid)
			)
			(fill no)
			(layer "F.Fab")
		)
		(pad "1" smd roundrect
			(at -0.48 0 180)
			(size 0.59 0.64)
			(layers "F.Cu" "F.Mask" "F.Paste")
			(roundrect_rratio 0.25)
			(net 2 "GND")
			(pintype "passive")
		)
		(pad "2" smd roundrect
			(at 0.48 0 180)
			(size 0.59 0.64)
			(layers "F.Cu" "F.Mask" "F.Paste")
			(roundrect_rratio 0.25)
			(net 44 "/DC-DC Converters/12V_ILIM")
			(pintype "passive")
		)
	)
	(footprint "antmicro-footprints:C_0402_1005Metric"
		(layer "F.Cu")
		(at 89.4 73.7 180)
		(descr "Capacitor SMD 0402")
		(tags "capacitor SMD 0402")
		(property "Reference" "C9"
			(at -6.3912 2.35 90)
			(layer "B.SilkS")
			(effects
				(font
					(size 0.7 0.7)
					(thickness 0.15)
				)
				(justify left bottom mirror)
			)
		)
		(property "Value" "C_1u_25V_0402"
			(at -1.022927 2.155213 0)
			(layer "F.Fab")
			(effects
				(font
					(size 0.7 0.7)
					(thickness 0.15)
				)
				(justify right bottom)
			)
		)
		(property "Datasheet" "https://www.murata.com/products/productdetail?partno=GRM155R61E105KE11%23"
			(at 0 0 180)
			(layer "F.Fab")
			(hide yes)
			(effects
				(font
					(size 1.27 1.27)
					(thickness 0.15)
				)
			)
		)
		(property "Description" "SMD Multilayer Ceramic Capacitor, 1 µF, 25 V, 0402 [1005 Metric], ± 10%, X5R, GRM Series"
			(at 0 0 180)
			(layer "F.Fab")
			(hide yes)
			(effects
				(font
					(size 1.27 1.27)
					(thickness 0.15)
				)
			)
		)
		(property "MPN" "GRM155R61E105KE11J"
			(at 0 0 180)
			(unlocked yes)
			(layer "F.Fab")
			(hide yes)
			(effects
				(font
					(size 1 1)
					(thickness 0.15)
				)
			)
		)
		(property "Manufacturer" "Murata"
			(at 0 0 180)
			(unlocked yes)
			(layer "F.Fab")
			(hide yes)
			(effects
				(font
					(size 1 1)
					(thickness 0.15)
				)
			)
		)
		(property "License" "Apache-2.0"
			(at 0 0 180)
			(unlocked yes)
			(layer "F.Fab")
			(hide yes)
			(effects
				(font
					(size 1 1)
					(thickness 0.15)
				)
			)
		)
		(property "Author" "Antmicro"
			(at 0 0 180)
			(unlocked yes)
			(layer "F.Fab")
			(hide yes)
			(effects
				(font
					(size 1 1)
					(thickness 0.15)
				)
			)
		)
		(property "Val" "1u"
			(at 0 0 180)
			(unlocked yes)
			(layer "F.Fab")
			(hide yes)
			(effects
				(font
					(size 1 1)
					(thickness 0.15)
				)
			)
		)
		(property "Voltage" "25V"
			(at 0 0 180)
			(unlocked yes)
			(layer "F.Fab")
			(hide yes)
			(effects
				(font
					(size 1 1)
					(thickness 0.15)
				)
			)
		)
		(property "Dielectric" "X5R"
			(at 0 0 180)
			(unlocked yes)
			(layer "F.Fab")
			(hide yes)
			(effects
				(font
					(size 1 1)
					(thickness 0.15)
				)
			)
		)
		(sheetname "/USB PD/")
		(sheetfile "usb_pd.kicad_sch")
		(attr smd)
		(fp_rect
			(start -0.925 -0.47)
			(end 0.925 0.47)
			(stroke
				(width 0.05)
				(type default)
			)
			(fill no)
			(layer "F.CrtYd")
		)
		(fp_line
			(start 0.504 0.248)
			(end -0.494 0.248)
			(stroke
				(width 0.15)
				(type solid)
			)
			(layer "F.Fab")
		)
		(fp_line
			(start 0.504 -0.25)
			(end 0.504 0.248)
			(stroke
				(width 0.15)
				(type solid)
			)
			(layer "F.Fab")
		)
		(fp_line
			(start -0.494 0.248)
			(end -0.494 -0.25)
			(stroke
				(width 0.15)
				(type solid)
			)
			(layer "F.Fab")
		)
		(fp_line
			(start -0.494 -0.25)
			(end 0.504 -0.25)
			(stroke
				(width 0.15)
				(type solid)
			)
			(layer "F.Fab")
		)
		(pad "1" smd roundrect
			(at -0.48 0 180)
			(size 0.59 0.64)
			(layers "F.Cu" "F.Mask" "F.Paste")
			(roundrect_rratio 0.25)
			(net 2 "GND")
			(pintype "passive")
		)
		(pad "2" smd roundrect
			(at 0.48 0 180)
			(size 0.59 0.64)
			(layers "F.Cu" "F.Mask" "F.Paste")
			(roundrect_rratio 0.25)
			(net 15 "Net-(U1-VREG_1V2)")
			(pintype "passive")
		)
	)
	(footprint "antmicro-footprints:TP_SMD_0.75mm"
		(layer "F.Cu")
		(at 87.126 81.275)
		(property "Reference" "TP4"
			(at 13.956 -3.4 0)
			(layer "F.SilkS")
			(hide yes)
			(effects
				(font
					(size 0.7 0.7)
					(thickness 0.15)
				)
				(justify left bottom)
			)
		)
		(property "Value" "TP_0.75mm_SMD"
			(at 0 1.2 0)
			(layer "F.Fab")
			(effects
				(font
					(size 0.7 0.7)
					(thickness 0.15)
				)
				(justify left bottom)
			)
		)
		(property "Description" "SMT test point"
			(at 0 0 0)
			(layer "F.Fab")
			(hide yes)
			(effects
				(font
					(size 1.27 1.27)
					(thickness 0.15)
				)
			)
		)
		(property "MPN" ""
			(at 0 0 0)
			(unlocked yes)
			(layer "F.Fab")
			(hide yes)
			(effects
				(font
					(size 1 1)
					(thickness 0.15)
				)
			)
		)
		(property "Manufacturer" ""
			(at 0 0 0)
			(unlocked yes)
			(layer "F.Fab")
			(hide yes)
			(effects
				(font
					(size 1 1)
					(thickness 0.15)
				)
			)
		)
		(property "Author" "Antmicro"
			(at 0 0 0)
			(unlocked yes)
			(layer "F.Fab")
			(hide yes)
			(effects
				(font
					(size 1 1)
					(thickness 0.15)
				)
			)
		)
		(property "License" "Apache-2.0"
			(at 0 0 0)
			(unlocked yes)
			(layer "F.Fab")
			(hide yes)
			(effects
				(font
					(size 1 1)
					(thickness 0.15)
				)
			)
		)
		(sheetname "/USB PD/")
		(sheetfile "usb_pd.kicad_sch")
		(attr exclude_from_bom)
		(fp_circle
			(center 0 0)
			(end 0.475 0)
			(stroke
				(width 0.05)
				(type default)
			)
			(fill no)
			(layer "F.CrtYd")
		)
		(pad "1" smd circle
			(at 0 0)
			(size 0.75 0.75)
			(layers "F.Cu" "F.Mask")
			(net 3 "VCC")
			(pinfunction "1")
			(pintype "passive")
		)
	)
	(footprint "antmicro-footprints:R_0402_1005Metric"
		(layer "F.Cu")
		(at 91.851 106.05 90)
		(descr "Resistor SMD 0402")
		(tags "resistor SMD 0402")
		(property "Reference" "R28"
			(at -1.075 -0.725 90)
			(layer "F.SilkS")
			(effects
				(font
					(size 0.7 0.7)
					(thickness 0.15)
				)
				(justify left bottom)
			)
		)
		(property "Value" "R_2k2_0402"
			(at -1.011843 1.772047 90)
			(layer "F.Fab")
			(effects
				(font
					(size 0.7 0.7)
					(thickness 0.15)
				)
				(justify left bottom)
			)
		)
		(property "Datasheet" "https://www.bourns.com/docs/product-datasheets/cr.pdf"
			(at 0 0 90)
			(layer "F.Fab")
			(hide yes)
			(effects
				(font
					(size 1.27 1.27)
					(thickness 0.15)
				)
			)
		)
		(property "Description" "SMD Chip Resistor, 2.2 kohm, ± 1%, 62.5 mW, 0402 [1005 Metric], Thick Film, General Purpose"
			(at 0 0 90)
			(layer "F.Fab")
			(hide yes)
			(effects
				(font
					(size 1.27 1.27)
					(thickness 0.15)
				)
			)
		)
		(property "MPN" "CR0402-FX-2201GLF"
			(at 0 0 90)
			(unlocked yes)
			(layer "F.Fab")
			(hide yes)
			(effects
				(font
					(size 1 1)
					(thickness 0.15)
				)
			)
		)
		(property "Manufacturer" "Bourns"
			(at 0 0 90)
			(unlocked yes)
			(layer "F.Fab")
			(hide yes)
			(effects
				(font
					(size 1 1)
					(thickness 0.15)
				)
			)
		)
		(property "License" "Apache-2.0"
			(at 0 0 90)
			(unlocked yes)
			(layer "F.Fab")
			(hide yes)
			(effects
				(font
					(size 1 1)
					(thickness 0.15)
				)
			)
		)
		(property "Author" "Antmicro"
			(at 0 0 90)
			(unlocked yes)
			(layer "F.Fab")
			(hide yes)
			(effects
				(font
					(size 1 1)
					(thickness 0.15)
				)
			)
		)
		(property "Val" "2k2"
			(at 0 0 90)
			(unlocked yes)
			(layer "F.Fab")
			(hide yes)
			(effects
				(font
					(size 1 1)
					(thickness 0.15)
				)
			)
		)
		(property "Tolerance" "1%"
			(at 0 0 90)
			(unlocked yes)
			(layer "F.Fab")
			(hide yes)
			(effects
				(font
					(size 1 1)
					(thickness 0.15)
				)
			)
		)
		(sheetname "/DC-DC Converters/")
		(sheetfile "dc-dc_converters.kicad_sch")
		(attr smd)
		(fp_rect
			(start -0.925 -0.47)
			(end 0.925 0.47)
			(stroke
				(width 0.05)
				(type default)
			)
			(fill no)
			(layer "F.CrtYd")
		)
		(fp_rect
			(start -0.5 -0.25)
			(end 0.5 0.25)
			(stroke
				(width 0.15)
				(type solid)
			)
			(fill no)
			(layer "F.Fab")
		)
		(pad "1" smd roundrect
			(at -0.48 0 90)
			(size 0.59 0.64)
			(layers "F.Cu" "F.Mask" "F.Paste")
			(roundrect_rratio 0.25)
			(net 65 "Net-(D4-A)")
			(pintype "passive")
		)
		(pad "2" smd roundrect
			(at 0.48 0 90)
			(size 0.59 0.64)
			(layers "F.Cu" "F.Mask" "F.Paste")
			(roundrect_rratio 0.25)
			(net 5 "+12V")
			(pintype "passive")
		)
	)
	(footprint "antmicro-footprints:TP_SMD_0.75mm"
		(layer "F.Cu")
		(at 89.676 105.05)
		(property "Reference" "TP7"
			(at -12.203 -1.909 0)
			(layer "F.SilkS")
			(hide yes)
			(effects
				(font
					(size 0.7 0.7)
					(thickness 0.15)
				)
				(justify left bottom)
			)
		)
		(property "Value" "TP_0.75mm_SMD"
			(at 0 1.2 0)
			(layer "F.Fab")
			(effects
				(font
					(size 0.7 0.7)
					(thickness 0.15)
				)
				(justify left bottom)
			)
		)
		(property "Description" "SMT test point"
			(at 0 0 0)
			(layer "F.Fab")
			(hide yes)
			(effects
				(font
					(size 1.27 1.27)
					(thickness 0.15)
				)
			)
		)
		(property "MPN" ""
			(at 0 0 0)
			(unlocked yes)
			(layer "F.Fab")
			(hide yes)
			(effects
				(font
					(size 1 1)
					(thickness 0.15)
				)
			)
		)
		(property "Manufacturer" ""
			(at 0 0 0)
			(unlocked yes)
			(layer "F.Fab")
			(hide yes)
			(effects
				(font
					(size 1 1)
					(thickness 0.15)
				)
			)
		)
		(property "Author" "Antmicro"
			(at 0 0 0)
			(unlocked yes)
			(layer "F.Fab")
			(hide yes)
			(effects
				(font
					(size 1 1)
					(thickness 0.15)
				)
			)
		)
		(property "License" "Apache-2.0"
			(at 0 0 0)
			(unlocked yes)
			(layer "F.Fab")
			(hide yes)
			(effects
				(font
					(size 1 1)
					(thickness 0.15)
				)
			)
		)
		(sheetname "/DC-DC Converters/")
		(sheetfile "dc-dc_converters.kicad_sch")
		(attr exclude_from_bom)
		(fp_circle
			(center 0 0)
			(end 0.475 0)
			(stroke
				(width 0.05)
				(type default)
			)
			(fill no)
			(layer "F.CrtYd")
		)
		(pad "1" smd circle
			(at 0 0)
			(size 0.75 0.75)
			(layers "F.Cu" "F.Mask")
			(net 5 "+12V")
			(pinfunction "1")
			(pintype "passive")
		)
	)
	(footprint "antmicro-footprints:R_0402_1005Metric"
		(layer "F.Cu")
		(at 100.5 89.6 180)
		(descr "Resistor SMD 0402")
		(tags "resistor SMD 0402")
		(property "Reference" "R15"
			(at -1.8 -1.2 90)
			(layer "F.SilkS")
			(effects
				(font
					(size 0.7 0.7)
					(thickness 0.15)
				)
				(justify left bottom)
			)
		)
		(property "Value" "R_8k66_0402"
			(at -1.011843 1.772047 0)
			(layer "F.Fab")
			(effects
				(font
					(size 0.7 0.7)
					(thickness 0.15)
				)
				(justify right bottom)
			)
		)
		(property "Datasheet" "https://www.bourns.com/docs/product-datasheets/cr.pdf"
			(at 0 0 180)
			(layer "F.Fab")
			(hide yes)
			(effects
				(font
					(size 1.27 1.27)
					(thickness 0.15)
				)
			)
		)
		(property "Description" "SMD Chip Resistor"
			(at 0 0 180)
			(layer "F.Fab")
			(hide yes)
			(effects
				(font
					(size 1.27 1.27)
					(thickness 0.15)
				)
			)
		)
		(property "Manufacturer" "Bourns"
			(at 0 0 180)
			(unlocked yes)
			(layer "F.Fab")
			(hide yes)
			(effects
				(font
					(size 1 1)
					(thickness 0.15)
				)
			)
		)
		(property "MPN" "CR0402-FX-8661GLF"
			(at 0 0 180)
			(unlocked yes)
			(layer "F.Fab")
			(hide yes)
			(effects
				(font
					(size 1 1)
					(thickness 0.15)
				)
			)
		)
		(property "Val" "8k66"
			(at 0 0 180)
			(unlocked yes)
			(layer "F.Fab")
			(hide yes)
			(effects
				(font
					(size 1 1)
					(thickness 0.15)
				)
			)
		)
		(property "License" "Apache-2.0"
			(at 0 0 180)
			(unlocked yes)
			(layer "F.Fab")
			(hide yes)
			(effects
				(font
					(size 1 1)
					(thickness 0.15)
				)
			)
		)
		(property "Author" "Antmicro"
			(at 0 0 180)
			(unlocked yes)
			(layer "F.Fab")
			(hide yes)
			(effects
				(font
					(size 1 1)
					(thickness 0.15)
				)
			)
		)
		(property "Tolerance" "1%"
			(at 0 0 180)
			(unlocked yes)
			(layer "F.Fab")
			(hide yes)
			(effects
				(font
					(size 1 1)
					(thickness 0.15)
				)
			)
		)
		(sheetname "/DC-DC Converters/")
		(sheetfile "dc-dc_converters.kicad_sch")
		(attr smd exclude_from_pos_files exclude_from_bom dnp)
		(fp_rect
			(start -0.925 -0.47)
			(end 0.925 0.47)
			(stroke
				(width 0.05)
				(type default)
			)
			(fill no)
			(layer "F.CrtYd")
		)
		(fp_rect
			(start -0.5 -0.25)
			(end 0.5 0.25)
			(stroke
				(width 0.15)
				(type solid)
			)
			(fill no)
			(layer "F.Fab")
		)
		(pad "1" smd roundrect
			(at -0.48 0 180)
			(size 0.59 0.64)
			(layers "F.Cu" "F.Mask" "F.Paste")
			(roundrect_rratio 0.25)
			(net 8 "Net-(L1-Pad1)")
			(pintype "passive")
		)
		(pad "2" smd roundrect
			(at 0.48 0 180)
			(size 0.59 0.64)
			(layers "F.Cu" "F.Mask" "F.Paste")
			(roundrect_rratio 0.25)
			(net 19 "/DC-DC Converters/12V_SNS")
			(pintype "passive")
		)
	)
)
